(kicad_pcb
	(version 20260206)
	(generator "pcbnew")
	(generator_version "10.0")
	(general
		(thickness 1.6)
		(legacy_teardrops no)
	)
	(paper "A4")
	(title_block
		(title "03242023_DA0F0TMBIJ0_F0T_Motherboard_J_brd_V01_OCP.brd")
		(comment 1 "Grand Teton / footprints 5942-5947 of 6105")
	)
	(layers
		(0 "F.Cu" signal "TOP")
		(4 "In1.Cu" signal "GND")
		(6 "In2.Cu" signal "IN1")
		(8 "In3.Cu" signal "GND1")
		(10 "In4.Cu" signal "IN2")
		(12 "In5.Cu" signal "GND2")
		(14 "In6.Cu" signal "IN3")
		(16 "In7.Cu" signal "GND3")
		(18 "In8.Cu" signal "VCC")
		(20 "In9.Cu" signal "VCC1")
		(22 "In10.Cu" signal "GND4")
		(24 "In11.Cu" signal "IN4")
		(26 "In12.Cu" signal "GND5")
		(28 "In13.Cu" signal "IN5")
		(30 "In14.Cu" signal "GND6")
		(32 "In15.Cu" signal "IN6")
		(34 "In16.Cu" signal "GND7")
		(2 "B.Cu" signal "BOTTOM")
		(9 "F.Adhes" user "F.Adhesive")
		(11 "B.Adhes" user "B.Adhesive")
		(13 "F.Paste" user "Package Geometry/Pastemask Top")
		(15 "B.Paste" user "Package Geometry/Pastemask Bottom")
		(5 "F.SilkS" user "Ref Des/Silkscreen Top")
		(7 "B.SilkS" user "Ref Des/Silkscreen Bottom")
		(1 "F.Mask" user "Board Geometry/Soldermask Top")
		(3 "B.Mask" user "Board Geometry/Soldermask Bottom")
		(17 "Dwgs.User" user "User.Drawings")
		(19 "Cmts.User" user "User.Comments")
		(21 "Eco1.User" user "User.Eco1")
		(23 "Eco2.User" user "User.Eco2")
		(25 "Edge.Cuts" user "Board Geometry/Outline")
		(27 "Margin" user)
		(31 "F.CrtYd" user "Package Geometry/Place Bound Top")
		(29 "B.CrtYd" user "Package Geometry/Place Bound Bottom")
		(35 "F.Fab" user "Ref Des/Assembly Top")
		(33 "B.Fab" user "Ref Des/Assembly Bottom")
	)
	(footprint ""
		(layer "B.Cu")
		(at 334.62849 -51.343814)
		(property "Reference" "C1207"
			(at 0 0 0)
			(layer "B.SilkS")
			(hide yes)
			(effects
				(font
					(size 1.27 1.27)
				)
				(justify mirror)
			)
		)
		(property "Value" ""
			(at 0 0 0)
			(layer "B.Fab")
			(effects
				(font
					(size 1.27 1.27)
				)
				(justify mirror)
			)
		)
		(duplicate_pad_numbers_are_jumpers no)
		(fp_line
			(start -0.7874 -0.4064)
			(end -0.7874 0.4064)
			(stroke
				(width 0.1524)
				(type default)
			)
			(layer "B.SilkS")
		)
		(fp_line
			(start -0.7874 0.4064)
			(end 0.7874 0.4064)
			(stroke
				(width 0.1524)
				(type default)
			)
			(layer "B.SilkS")
		)
		(fp_line
			(start 0.7874 -0.4064)
			(end -0.7874 -0.4064)
			(stroke
				(width 0.1524)
				(type default)
			)
			(layer "B.SilkS")
		)
		(fp_line
			(start 0.7874 0.4064)
			(end 0.7874 -0.4064)
			(stroke
				(width 0.1524)
				(type default)
			)
			(layer "B.SilkS")
		)
		(fp_line
			(start -0.67945 -0.3048)
			(end -0.67945 0.3048)
			(stroke
				(width 0.1)
				(type default)
			)
			(layer "B.Fab")
		)
		(fp_line
			(start -0.67945 0.3048)
			(end -0.120396 0.3048)
			(stroke
				(width 0.1)
				(type default)
			)
			(layer "B.Fab")
		)
		(fp_line
			(start -0.12065 -0.3048)
			(end -0.67945 -0.3048)
			(stroke
				(width 0.1)
				(type default)
			)
			(layer "B.Fab")
		)
		(fp_line
			(start -0.12065 -0.2794)
			(end -0.12065 -0.3048)
			(stroke
				(width 0.1)
				(type default)
			)
			(layer "B.Fab")
		)
		(fp_line
			(start -0.120396 0.2794)
			(end 0.12065 0.2794)
			(stroke
				(width 0.1)
				(type default)
			)
			(layer "B.Fab")
		)
		(fp_line
			(start -0.120396 0.3048)
			(end -0.120396 0.2794)
			(stroke
				(width 0.1)
				(type default)
			)
			(layer "B.Fab")
		)
		(fp_line
			(start 0.12065 -0.305054)
			(end 0.12065 -0.2794)
			(stroke
				(width 0.1)
				(type default)
			)
			(layer "B.Fab")
		)
		(fp_line
			(start 0.12065 -0.2794)
			(end -0.12065 -0.2794)
			(stroke
				(width 0.1)
				(type default)
			)
			(layer "B.Fab")
		)
		(fp_line
			(start 0.12065 0.2794)
			(end 0.12065 0.3048)
			(stroke
				(width 0.1)
				(type default)
			)
			(layer "B.Fab")
		)
		(fp_line
			(start 0.12065 0.3048)
			(end 0.67945 0.3048)
			(stroke
				(width 0.1)
				(type default)
			)
			(layer "B.Fab")
		)
		(fp_line
			(start 0.67945 -0.305054)
			(end 0.12065 -0.305054)
			(stroke
				(width 0.1)
				(type default)
			)
			(layer "B.Fab")
		)
		(fp_line
			(start 0.67945 0.3048)
			(end 0.67945 -0.305054)
			(stroke
				(width 0.1)
				(type default)
			)
			(layer "B.Fab")
		)
		(pad "1" smd circle
			(at 0.40005 0 180)
			(size 0 0)
			(layers "B.Cu" "B.Mask" "B.Paste")
			(net "P1V8_PCH_AUX")
		)
		(pad "2" smd circle
			(at -0.40005 0 180)
			(size 0 0)
			(layers "B.Cu" "B.Mask" "B.Paste")
			(net "GND")
		)
	)
	(footprint ""
		(layer "B.Cu")
		(at 98.50374 -422.156128 90)
		(property "Reference" "R4546"
			(at 0 0 90)
			(layer "B.SilkS")
			(hide yes)
			(effects
				(font
					(size 1.27 1.27)
				)
				(justify mirror)
			)
		)
		(property "Value" ""
			(at 0 0 90)
			(layer "B.Fab")
			(effects
				(font
					(size 1.27 1.27)
				)
				(justify mirror)
			)
		)
		(duplicate_pad_numbers_are_jumpers no)
		(fp_line
			(start 0.7874 -0.4064)
			(end -0.7874 -0.4064)
			(stroke
				(width 0.1524)
				(type default)
			)
			(layer "B.SilkS")
		)
		(fp_line
			(start -0.7874 -0.4064)
			(end -0.7874 0.4064)
			(stroke
				(width 0.1524)
				(type default)
			)
			(layer "B.SilkS")
		)
		(fp_line
			(start 0.7874 0.4064)
			(end 0.7874 -0.4064)
			(stroke
				(width 0.1524)
				(type default)
			)
			(layer "B.SilkS")
		)
		(fp_line
			(start -0.7874 0.4064)
			(end 0.7874 0.4064)
			(stroke
				(width 0.1524)
				(type default)
			)
			(layer "B.SilkS")
		)
		(fp_line
			(start 0.67945 -0.305054)
			(end 0.12065 -0.305054)
			(stroke
				(width 0.1)
				(type default)
			)
			(layer "B.Fab")
		)
		(fp_line
			(start 0.12065 -0.305054)
			(end 0.12065 -0.2794)
			(stroke
				(width 0.1)
				(type default)
			)
			(layer "B.Fab")
		)
		(fp_line
			(start -0.12065 -0.3048)
			(end -0.67945 -0.3048)
			(stroke
				(width 0.1)
				(type default)
			)
			(layer "B.Fab")
		)
		(fp_line
			(start -0.67945 -0.3048)
			(end -0.67945 0.3048)
			(stroke
				(width 0.1)
				(type default)
			)
			(layer "B.Fab")
		)
		(fp_line
			(start 0.12065 -0.2794)
			(end -0.12065 -0.2794)
			(stroke
				(width 0.1)
				(type default)
			)
			(layer "B.Fab")
		)
		(fp_line
			(start -0.12065 -0.2794)
			(end -0.12065 -0.3048)
			(stroke
				(width 0.1)
				(type default)
			)
			(layer "B.Fab")
		)
		(fp_line
			(start 0.12065 0.2794)
			(end 0.12065 0.3048)
			(stroke
				(width 0.1)
				(type default)
			)
			(layer "B.Fab")
		)
		(fp_line
			(start -0.120396 0.2794)
			(end 0.12065 0.2794)
			(stroke
				(width 0.1)
				(type default)
			)
			(layer "B.Fab")
		)
		(fp_line
			(start 0.67945 0.3048)
			(end 0.67945 -0.305054)
			(stroke
				(width 0.1)
				(type default)
			)
			(layer "B.Fab")
		)
		(fp_line
			(start 0.12065 0.3048)
			(end 0.67945 0.3048)
			(stroke
				(width 0.1)
				(type default)
			)
			(layer "B.Fab")
		)
		(fp_line
			(start -0.120396 0.3048)
			(end -0.120396 0.2794)
			(stroke
				(width 0.1)
				(type default)
			)
			(layer "B.Fab")
		)
		(fp_line
			(start -0.67945 0.3048)
			(end -0.120396 0.3048)
			(stroke
				(width 0.1)
				(type default)
			)
			(layer "B.Fab")
		)
		(pad "1" smd circle
			(at 0.40005 0 270)
			(size 0 0)
			(layers "B.Cu" "B.Mask" "B.Paste")
			(net "P3V3_AUX")
		)
		(pad "2" smd circle
			(at -0.40005 0 270)
			(size 0 0)
			(layers "B.Cu" "B.Mask" "B.Paste")
			(net "HGX_DETECT_N_ISO")
		)
	)
	(footprint ""
		(layer "B.Cu")
		(at 258.384802 -105.911396)
		(property "Reference" "R1194"
			(at 0 0 0)
			(layer "B.SilkS")
			(hide yes)
			(effects
				(font
					(size 1.27 1.27)
				)
				(justify mirror)
			)
		)
		(property "Value" ""
			(at 0 0 0)
			(layer "B.Fab")
			(effects
				(font
					(size 1.27 1.27)
				)
				(justify mirror)
			)
		)
		(duplicate_pad_numbers_are_jumpers no)
		(fp_line
			(start -0.7874 -0.4064)
			(end -0.7874 0.4064)
			(stroke
				(width 0.1524)
				(type default)
			)
			(layer "B.SilkS")
		)
		(fp_line
			(start -0.7874 0.4064)
			(end 0.7874 0.4064)
			(stroke
				(width 0.1524)
				(type default)
			)
			(layer "B.SilkS")
		)
		(fp_line
			(start 0.7874 -0.4064)
			(end -0.7874 -0.4064)
			(stroke
				(width 0.1524)
				(type default)
			)
			(layer "B.SilkS")
		)
		(fp_line
			(start 0.7874 0.4064)
			(end 0.7874 -0.4064)
			(stroke
				(width 0.1524)
				(type default)
			)
			(layer "B.SilkS")
		)
		(fp_line
			(start -0.67945 -0.3048)
			(end -0.67945 0.3048)
			(stroke
				(width 0.1)
				(type default)
			)
			(layer "B.Fab")
		)
		(fp_line
			(start -0.67945 0.3048)
			(end -0.120396 0.3048)
			(stroke
				(width 0.1)
				(type default)
			)
			(layer "B.Fab")
		)
		(fp_line
			(start -0.12065 -0.3048)
			(end -0.67945 -0.3048)
			(stroke
				(width 0.1)
				(type default)
			)
			(layer "B.Fab")
		)
		(fp_line
			(start -0.12065 -0.2794)
			(end -0.12065 -0.3048)
			(stroke
				(width 0.1)
				(type default)
			)
			(layer "B.Fab")
		)
		(fp_line
			(start -0.120396 0.2794)
			(end 0.12065 0.2794)
			(stroke
				(width 0.1)
				(type default)
			)
			(layer "B.Fab")
		)
		(fp_line
			(start -0.120396 0.3048)
			(end -0.120396 0.2794)
			(stroke
				(width 0.1)
				(type default)
			)
			(layer "B.Fab")
		)
		(fp_line
			(start 0.12065 -0.305054)
			(end 0.12065 -0.2794)
			(stroke
				(width 0.1)
				(type default)
			)
			(layer "B.Fab")
		)
		(fp_line
			(start 0.12065 -0.2794)
			(end -0.12065 -0.2794)
			(stroke
				(width 0.1)
				(type default)
			)
			(layer "B.Fab")
		)
		(fp_line
			(start 0.12065 0.2794)
			(end 0.12065 0.3048)
			(stroke
				(width 0.1)
				(type default)
			)
			(layer "B.Fab")
		)
		(fp_line
			(start 0.12065 0.3048)
			(end 0.67945 0.3048)
			(stroke
				(width 0.1)
				(type default)
			)
			(layer "B.Fab")
		)
		(fp_line
			(start 0.67945 -0.305054)
			(end 0.12065 -0.305054)
			(stroke
				(width 0.1)
				(type default)
			)
			(layer "B.Fab")
		)
		(fp_line
			(start 0.67945 0.3048)
			(end 0.67945 -0.305054)
			(stroke
				(width 0.1)
				(type default)
			)
			(layer "B.Fab")
		)
		(pad "1" smd circle
			(at 0.40005 0 180)
			(size 0 0)
			(layers "B.Cu" "B.Mask" "B.Paste")
			(net "P3V3_AUX")
		)
		(pad "2" smd circle
			(at -0.40005 0 180)
			(size 0 0)
			(layers "B.Cu" "B.Mask" "B.Paste")
			(net "FM_CK440_MXCK_25M_100M")
		)
	)
	(footprint ""
		(layer "B.Cu")
		(at 433.564792 -193.565272 -90)
		(property "Reference" "R705"
			(at 0 0 90)
			(layer "B.SilkS")
			(hide yes)
			(effects
				(font
					(size 1.27 1.27)
				)
				(justify mirror)
			)
		)
		(property "Value" ""
			(at 0 0 90)
			(layer "B.Fab")
			(effects
				(font
					(size 1.27 1.27)
				)
				(justify mirror)
			)
		)
		(duplicate_pad_numbers_are_jumpers no)
		(fp_line
			(start -0.7874 0.4064)
			(end 0.7874 0.4064)
			(stroke
				(width 0.1524)
				(type default)
			)
			(layer "B.SilkS")
		)
		(fp_line
			(start 0.7874 0.4064)
			(end 0.7874 -0.4064)
			(stroke
				(width 0.1524)
				(type default)
			)
			(layer "B.SilkS")
		)
		(fp_line
			(start -0.7874 -0.4064)
			(end -0.7874 0.4064)
			(stroke
				(width 0.1524)
				(type default)
			)
			(layer "B.SilkS")
		)
		(fp_line
			(start 0.7874 -0.4064)
			(end -0.7874 -0.4064)
			(stroke
				(width 0.1524)
				(type default)
			)
			(layer "B.SilkS")
		)
		(fp_line
			(start -0.67945 0.3048)
			(end -0.120396 0.3048)
			(stroke
				(width 0.1)
				(type default)
			)
			(layer "B.Fab")
		)
		(fp_line
			(start -0.120396 0.3048)
			(end -0.120396 0.2794)
			(stroke
				(width 0.1)
				(type default)
			)
			(layer "B.Fab")
		)
		(fp_line
			(start 0.12065 0.3048)
			(end 0.67945 0.3048)
			(stroke
				(width 0.1)
				(type default)
			)
			(layer "B.Fab")
		)
		(fp_line
			(start 0.67945 0.3048)
			(end 0.67945 -0.305054)
			(stroke
				(width 0.1)
				(type default)
			)
			(layer "B.Fab")
		)
		(fp_line
			(start -0.120396 0.2794)
			(end 0.12065 0.2794)
			(stroke
				(width 0.1)
				(type default)
			)
			(layer "B.Fab")
		)
		(fp_line
			(start 0.12065 0.2794)
			(end 0.12065 0.3048)
			(stroke
				(width 0.1)
				(type default)
			)
			(layer "B.Fab")
		)
		(fp_line
			(start -0.12065 -0.2794)
			(end -0.12065 -0.3048)
			(stroke
				(width 0.1)
				(type default)
			)
			(layer "B.Fab")
		)
		(fp_line
			(start 0.12065 -0.2794)
			(end -0.12065 -0.2794)
			(stroke
				(width 0.1)
				(type default)
			)
			(layer "B.Fab")
		)
		(fp_line
			(start -0.67945 -0.3048)
			(end -0.67945 0.3048)
			(stroke
				(width 0.1)
				(type default)
			)
			(layer "B.Fab")
		)
		(fp_line
			(start -0.12065 -0.3048)
			(end -0.67945 -0.3048)
			(stroke
				(width 0.1)
				(type default)
			)
			(layer "B.Fab")
		)
		(fp_line
			(start 0.12065 -0.305054)
			(end 0.12065 -0.2794)
			(stroke
				(width 0.1)
				(type default)
			)
			(layer "B.Fab")
		)
		(fp_line
			(start 0.67945 -0.305054)
			(end 0.12065 -0.305054)
			(stroke
				(width 0.1)
				(type default)
			)
			(layer "B.Fab")
		)
		(pad "1" smd circle
			(at 0.40005 0 90)
			(size 0 0)
			(layers "B.Cu" "B.Mask" "B.Paste")
			(net "RST_PLD_CPU0_DRAM_GH_N")
		)
		(pad "2" smd circle
			(at -0.40005 0 90)
			(size 0 0)
			(layers "B.Cu" "B.Mask" "B.Paste")
			(net "GND")
		)
	)
	(footprint ""
		(layer "B.Cu")
		(at 12.666472 -183.482996)
		(property "Reference" "R2480"
			(at 0 0 0)
			(layer "B.SilkS")
			(hide yes)
			(effects
				(font
					(size 1.27 1.27)
				)
				(justify mirror)
			)
		)
		(property "Value" ""
			(at 0 0 0)
			(layer "B.Fab")
			(effects
				(font
					(size 1.27 1.27)
				)
				(justify mirror)
			)
		)
		(duplicate_pad_numbers_are_jumpers no)
		(fp_line
			(start -0.7874 -0.4064)
			(end -0.7874 0.4064)
			(stroke
				(width 0.1524)
				(type default)
			)
			(layer "B.SilkS")
		)
		(fp_line
			(start -0.7874 0.4064)
			(end 0.7874 0.4064)
			(stroke
				(width 0.1524)
				(type default)
			)
			(layer "B.SilkS")
		)
		(fp_line
			(start 0.7874 -0.4064)
			(end -0.7874 -0.4064)
			(stroke
				(width 0.1524)
				(type default)
			)
			(layer "B.SilkS")
		)
		(fp_line
			(start 0.7874 0.4064)
			(end 0.7874 -0.4064)
			(stroke
				(width 0.1524)
				(type default)
			)
			(layer "B.SilkS")
		)
		(fp_line
			(start -0.67945 -0.3048)
			(end -0.67945 0.3048)
			(stroke
				(width 0.1)
				(type default)
			)
			(layer "B.Fab")
		)
		(fp_line
			(start -0.67945 0.3048)
			(end -0.120396 0.3048)
			(stroke
				(width 0.1)
				(type default)
			)
			(layer "B.Fab")
		)
		(fp_line
			(start -0.12065 -0.3048)
			(end -0.67945 -0.3048)
			(stroke
				(width 0.1)
				(type default)
			)
			(layer "B.Fab")
		)
		(fp_line
			(start -0.12065 -0.2794)
			(end -0.12065 -0.3048)
			(stroke
				(width 0.1)
				(type default)
			)
			(layer "B.Fab")
		)
		(fp_line
			(start -0.120396 0.2794)
			(end 0.12065 0.2794)
			(stroke
				(width 0.1)
				(type default)
			)
			(layer "B.Fab")
		)
		(fp_line
			(start -0.120396 0.3048)
			(end -0.120396 0.2794)
			(stroke
				(width 0.1)
				(type default)
			)
			(layer "B.Fab")
		)
		(fp_line
			(start 0.12065 -0.305054)
			(end 0.12065 -0.2794)
			(stroke
				(width 0.1)
				(type default)
			)
			(layer "B.Fab")
		)
		(fp_line
			(start 0.12065 -0.2794)
			(end -0.12065 -0.2794)
			(stroke
				(width 0.1)
				(type default)
			)
			(layer "B.Fab")
		)
		(fp_line
			(start 0.12065 0.2794)
			(end 0.12065 0.3048)
			(stroke
				(width 0.1)
				(type default)
			)
			(layer "B.Fab")
		)
		(fp_line
			(start 0.12065 0.3048)
			(end 0.67945 0.3048)
			(stroke
				(width 0.1)
				(type default)
			)
			(layer "B.Fab")
		)
		(fp_line
			(start 0.67945 -0.305054)
			(end 0.12065 -0.305054)
			(stroke
				(width 0.1)
				(type default)
			)
			(layer "B.Fab")
		)
		(fp_line
			(start 0.67945 0.3048)
			(end 0.67945 -0.305054)
			(stroke
				(width 0.1)
				(type default)
			)
			(layer "B.Fab")
		)
		(pad "1" smd circle
			(at 0.40005 0 180)
			(size 0 0)
			(layers "B.Cu" "B.Mask" "B.Paste")
			(net "SMB_PEHPCPU1_LVC3_SDA_R0")
		)
		(pad "2" smd circle
			(at -0.40005 0 180)
			(size 0 0)
			(layers "B.Cu" "B.Mask" "B.Paste")
			(net "SMB_PEHPCPU1_LVC3_SDA")
		)
	)
	(footprint ""
		(layer "B.Cu")
		(at 68.337684 -183.303926 -90)
		(property "Reference" "R156"
			(at 0 0 90)
			(layer "B.SilkS")
			(hide yes)
			(effects
				(font
					(size 1.27 1.27)
				)
				(justify mirror)
			)
		)
		(property "Value" ""
			(at 0 0 90)
			(layer "B.Fab")
			(effects
				(font
					(size 1.27 1.27)
				)
				(justify mirror)
			)
		)
		(duplicate_pad_numbers_are_jumpers no)
		(fp_line
			(start -0.7874 0.4064)
			(end 0.7874 0.4064)
			(stroke
				(width 0.1524)
				(type default)
			)
			(layer "B.SilkS")
		)
		(fp_line
			(start 0.7874 0.4064)
			(end 0.7874 -0.4064)
			(stroke
				(width 0.1524)
				(type default)
			)
			(layer "B.SilkS")
		)
		(fp_line
			(start -0.7874 -0.4064)
			(end -0.7874 0.4064)
			(stroke
				(width 0.1524)
				(type default)
			)
			(layer "B.SilkS")
		)
		(fp_line
			(start 0.7874 -0.4064)
			(end -0.7874 -0.4064)
			(stroke
				(width 0.1524)
				(type default)
			)
			(layer "B.SilkS")
		)
		(fp_line
			(start -0.67945 0.3048)
			(end -0.120396 0.3048)
			(stroke
				(width 0.1)
				(type default)
			)
			(layer "B.Fab")
		)
		(fp_line
			(start -0.120396 0.3048)
			(end -0.120396 0.2794)
			(stroke
				(width 0.1)
				(type default)
			)
			(layer "B.Fab")
		)
		(fp_line
			(start 0.12065 0.3048)
			(end 0.67945 0.3048)
			(stroke
				(width 0.1)
				(type default)
			)
			(layer "B.Fab")
		)
		(fp_line
			(start 0.67945 0.3048)
			(end 0.67945 -0.305054)
			(stroke
				(width 0.1)
				(type default)
			)
			(layer "B.Fab")
		)
		(fp_line
			(start -0.120396 0.2794)
			(end 0.12065 0.2794)
			(stroke
				(width 0.1)
				(type default)
			)
			(layer "B.Fab")
		)
		(fp_line
			(start 0.12065 0.2794)
			(end 0.12065 0.3048)
			(stroke
				(width 0.1)
				(type default)
			)
			(layer "B.Fab")
		)
		(fp_line
			(start -0.12065 -0.2794)
			(end -0.12065 -0.3048)
			(stroke
				(width 0.1)
				(type default)
			)
			(layer "B.Fab")
		)
		(fp_line
			(start 0.12065 -0.2794)
			(end -0.12065 -0.2794)
			(stroke
				(width 0.1)
				(type default)
			)
			(layer "B.Fab")
		)
		(fp_line
			(start -0.67945 -0.3048)
			(end -0.67945 0.3048)
			(stroke
				(width 0.1)
				(type default)
			)
			(layer "B.Fab")
		)
		(fp_line
			(start -0.12065 -0.3048)
			(end -0.67945 -0.3048)
			(stroke
				(width 0.1)
				(type default)
			)
			(layer "B.Fab")
		)
		(fp_line
			(start 0.12065 -0.305054)
			(end 0.12065 -0.2794)
			(stroke
				(width 0.1)
				(type default)
			)
			(layer "B.Fab")
		)
		(fp_line
			(start 0.67945 -0.305054)
			(end 0.12065 -0.305054)
			(stroke
				(width 0.1)
				(type default)
			)
			(layer "B.Fab")
		)
		(pad "1" smd circle
			(at 0.40005 0 90)
			(size 0 0)
			(layers "B.Cu" "B.Mask" "B.Paste")
			(net "PWRGD_CPU1_BUF_R")
		)
		(pad "2" smd circle
			(at -0.40005 0 90)
			(size 0 0)
			(layers "B.Cu" "B.Mask" "B.Paste")
			(net "PWRGD_CPU1_LVC1")
		)
	)
)
